(kicad_pcb
	(version 20241229)
	(generator "pcbnew")
	(generator_version "9.0")
	(general
		(thickness 1.599998)
		(legacy_teardrops no)
	)
	(paper "A4")
	(title_block
		(title "Artix - Datacenter Secure Control Module (DC-SCM)")
		(date "2024-11-06")
		(rev "1.1.3")
		(comment 9 "footprints 304-308 of 544")
	)
	(layers
		(0 "F.Cu" signal)
		(4 "In1.Cu" signal)
		(6 "In2.Cu" signal)
		(8 "In3.Cu" signal)
		(10 "In4.Cu" signal)
		(12 "In5.Cu" signal)
		(14 "In6.Cu" signal)
		(2 "B.Cu" signal)
		(9 "F.Adhes" user "F.Adhesive")
		(11 "B.Adhes" user "B.Adhesive")
		(13 "F.Paste" user)
		(15 "B.Paste" user)
		(5 "F.SilkS" user "F.Silkscreen")
		(7 "B.SilkS" user "B.Silkscreen")
		(1 "F.Mask" user)
		(3 "B.Mask" user)
		(17 "Dwgs.User" user "User.Drawings")
		(19 "Cmts.User" user "User.Comments")
		(21 "Eco1.User" user "User.Eco1")
		(23 "Eco2.User" user "User.Eco2")
		(25 "Edge.Cuts" user)
		(27 "Margin" user)
		(31 "F.CrtYd" user "F.Courtyard")
		(29 "B.CrtYd" user "B.Courtyard")
		(35 "F.Fab" user)
		(33 "B.Fab" user)
	)
	(footprint "antmicro-footprints:C_0201"
		(layer "B.Cu")
		(at 98.325 121.675)
		(descr "Capacitor SMD 0201")
		(tags "capacitor SMD 0201")
		(property "Reference" "C146"
			(at -22.425 0.825 0)
			(layer "B.SilkS")
			(effects
				(font
					(size 0.7 0.7)
					(thickness 0.15)
				)
				(justify right bottom mirror)
			)
		)
		(property "Value" "C_470n_0201"
			(at 0 -1.4 0)
			(layer "B.Fab")
			(effects
				(font
					(size 0.7 0.7)
					(thickness 0.15)
				)
				(justify right bottom mirror)
			)
		)
		(property "Datasheet" "https://product.tdk.com/en/search/capacitor/ceramic/mlcc/info?part_no=C0603X5R1A474M030BC"
			(at 0 0 0)
			(layer "F.Fab")
			(hide yes)
			(effects
				(font
					(size 1.27 1.27)
					(thickness 0.15)
				)
			)
		)
		(property "Description" "SMD Multilayer Ceramic Capacitor, 0.47 µF, 10 V, 0201 [0603 Metric], ± 20%, X5R, C"
			(at 0 0 0)
			(layer "F.Fab")
			(hide yes)
			(effects
				(font
					(size 1.27 1.27)
					(thickness 0.15)
				)
			)
		)
		(property "Author" "Antmicro"
			(at 0 0 0)
			(layer "B.Fab")
			(hide yes)
			(effects
				(font
					(size 1 1)
					(thickness 0.15)
				)
				(justify mirror)
			)
		)
		(property "Dielectric" ""
			(at 0 0 0)
			(layer "B.Fab")
			(hide yes)
			(effects
				(font
					(size 1 1)
					(thickness 0.15)
				)
				(justify mirror)
			)
		)
		(property "License" "Apache-2.0"
			(at 0 0 0)
			(layer "B.Fab")
			(hide yes)
			(effects
				(font
					(size 1 1)
					(thickness 0.15)
				)
				(justify mirror)
			)
		)
		(property "MPN" "C0603X5R1A474M030BC"
			(at 0 0 0)
			(layer "B.Fab")
			(hide yes)
			(effects
				(font
					(size 1 1)
					(thickness 0.15)
				)
				(justify mirror)
			)
		)
		(property "Manufacturer" "TDK"
			(at 0 0 0)
			(layer "B.Fab")
			(hide yes)
			(effects
				(font
					(size 1 1)
					(thickness 0.15)
				)
				(justify mirror)
			)
		)
		(property "Public" "False"
			(at 0 0 0)
			(layer "B.Fab")
			(hide yes)
			(effects
				(font
					(size 1 1)
					(thickness 0.15)
				)
				(justify mirror)
			)
		)
		(property "Val" "470n"
			(at 0 0 0)
			(layer "B.Fab")
			(hide yes)
			(effects
				(font
					(size 1 1)
					(thickness 0.15)
				)
				(justify mirror)
			)
		)
		(property "Voltage" ""
			(at 0 0 0)
			(layer "B.Fab")
			(hide yes)
			(effects
				(font
					(size 1 1)
					(thickness 0.15)
				)
				(justify mirror)
			)
		)
		(sheetname "/FPGA power supply/")
		(sheetfile "fpga-power-supply.kicad_sch")
		(attr smd)
		(fp_rect
			(start -0.7 0.35)
			(end 0.7 -0.35)
			(stroke
				(width 0.05)
				(type default)
			)
			(fill no)
			(layer "B.CrtYd")
		)
		(fp_rect
			(start 0.3 -0.15)
			(end -0.301 0.149)
			(stroke
				(width 0.15)
				(type solid)
			)
			(fill no)
			(layer "B.Fab")
		)
		(pad "" smd roundrect
			(at -0.349 0.002)
			(size 0.318 0.36)
			(layers "B.Paste")
			(roundrect_rratio 0.25)
		)
		(pad "" smd roundrect
			(at 0.341 0.002)
			(size 0.318 0.36)
			(layers "B.Paste")
			(roundrect_rratio 0.25)
		)
		(pad "1" smd roundrect
			(at -0.321 0.002)
			(size 0.46 0.4)
			(layers "B.Cu" "B.Mask")
			(roundrect_rratio 0.25)
			(net 1 "GND")
			(pintype "passive")
		)
		(pad "2" smd roundrect
			(at 0.32 0.002)
			(size 0.46 0.4)
			(layers "B.Cu" "B.Mask")
			(roundrect_rratio 0.25)
			(net 5 "VCC1V8")
			(pintype "passive")
		)
	)
	(footprint "antmicro-footprints:C_0402_1005Metric"
		(layer "B.Cu")
		(at 100.275 118.375 -90)
		(descr "Capacitor SMD 0402")
		(tags "capacitor SMD 0402")
		(property "Reference" "C148"
			(at -1.575 0.475 90)
			(layer "B.SilkS")
			(effects
				(font
					(size 0.7 0.7)
					(thickness 0.15)
				)
				(justify left bottom mirror)
			)
		)
		(property "Value" "C_470n_0402"
			(at 0 -1.4 90)
			(layer "B.Fab")
			(effects
				(font
					(size 0.7 0.7)
					(thickness 0.15)
				)
				(justify left bottom mirror)
			)
		)
		(property "Datasheet" "https://product.tdk.com/en/search/capacitor/ceramic/mlcc/info?part_no=C1005X5R1E474M050BB"
			(at 0 0 270)
			(layer "F.Fab")
			(hide yes)
			(effects
				(font
					(size 1.27 1.27)
					(thickness 0.15)
				)
			)
		)
		(property "Description" "SMD Multilayer Ceramic Capacitor, 0.47 µF, 25 V, 0402 [1005 Metric], ± 20%, X5R, C"
			(at 0 0 270)
			(layer "F.Fab")
			(hide yes)
			(effects
				(font
					(size 1.27 1.27)
					(thickness 0.15)
				)
			)
		)
		(property "Author" "Antmicro"
			(at -18.1 218.65 0)
			(layer "B.Fab")
			(hide yes)
			(effects
				(font
					(size 1 1)
					(thickness 0.15)
				)
				(justify mirror)
			)
		)
		(property "Dielectric" ""
			(at -18.1 218.65 0)
			(layer "B.Fab")
			(hide yes)
			(effects
				(font
					(size 1 1)
					(thickness 0.15)
				)
				(justify mirror)
			)
		)
		(property "License" "Apache-2.0"
			(at -18.1 218.65 0)
			(layer "B.Fab")
			(hide yes)
			(effects
				(font
					(size 1 1)
					(thickness 0.15)
				)
				(justify mirror)
			)
		)
		(property "MPN" "C1005X5R1E474M050BB"
			(at -18.1 218.65 0)
			(layer "B.Fab")
			(hide yes)
			(effects
				(font
					(size 1 1)
					(thickness 0.15)
				)
				(justify mirror)
			)
		)
		(property "Manufacturer" "TDK"
			(at -18.1 218.65 0)
			(layer "B.Fab")
			(hide yes)
			(effects
				(font
					(size 1 1)
					(thickness 0.15)
				)
				(justify mirror)
			)
		)
		(property "Val" "470n"
			(at -18.1 218.65 0)
			(layer "B.Fab")
			(hide yes)
			(effects
				(font
					(size 1 1)
					(thickness 0.15)
				)
				(justify mirror)
			)
		)
		(property "Voltage" ""
			(at -18.1 218.65 0)
			(layer "B.Fab")
			(hide yes)
			(effects
				(font
					(size 1 1)
					(thickness 0.15)
				)
				(justify mirror)
			)
		)
		(sheetname "/FPGA power supply/")
		(sheetfile "fpga-power-supply.kicad_sch")
		(attr smd)
		(fp_rect
			(start -0.925 0.47)
			(end 0.925 -0.47)
			(stroke
				(width 0.05)
				(type default)
			)
			(fill no)
			(layer "B.CrtYd")
		)
		(fp_line
			(start -0.494 0.25)
			(end 0.504 0.25)
			(stroke
				(width 0.15)
				(type solid)
			)
			(layer "B.Fab")
		)
		(fp_line
			(start 0.504 0.25)
			(end 0.504 -0.248)
			(stroke
				(width 0.15)
				(type solid)
			)
			(layer "B.Fab")
		)
		(fp_line
			(start -0.494 -0.248)
			(end -0.494 0.25)
			(stroke
				(width 0.15)
				(type solid)
			)
			(layer "B.Fab")
		)
		(fp_line
			(start 0.504 -0.248)
			(end -0.494 -0.248)
			(stroke
				(width 0.15)
				(type solid)
			)
			(layer "B.Fab")
		)
		(pad "1" smd roundrect
			(at -0.48 0 270)
			(size 0.59 0.64)
			(layers "B.Cu" "B.Mask" "B.Paste")
			(roundrect_rratio 0.25)
			(net 1 "GND")
			(pintype "passive")
		)
		(pad "2" smd roundrect
			(at 0.48 0 270)
			(size 0.59 0.64)
			(layers "B.Cu" "B.Mask" "B.Paste")
			(roundrect_rratio 0.25)
			(net 5 "VCC1V8")
			(pintype "passive")
		)
	)
	(footprint "antmicro-footprints:C_0402_1005Metric"
		(layer "B.Cu")
		(at 107.225 148.275 90)
		(descr "Capacitor SMD 0402")
		(tags "capacitor SMD 0402")
		(property "Reference" "C63"
			(at -2.925 0.375 90)
			(layer "B.SilkS")
			(effects
				(font
					(size 0.7 0.7)
					(thickness 0.15)
				)
				(justify right bottom mirror)
			)
		)
		(property "Value" "C_100n_6V3_0402"
			(at 0 -1.4 90)
			(layer "B.Fab")
			(effects
				(font
					(size 0.7 0.7)
					(thickness 0.15)
				)
				(justify right bottom mirror)
			)
		)
		(property "Datasheet" "https://www.passivecomponent.com/wp-content/uploads/datasheet/WTC_MLCC_General_Purpose.pdf"
			(at 0 0 90)
			(layer "F.Fab")
			(hide yes)
			(effects
				(font
					(size 1.27 1.27)
					(thickness 0.15)
				)
			)
		)
		(property "Description" "SMT Multilayer Ceramic Capacitor, 0.1 µF, 6.3 V, 0402 [1005 Metric], ± 10%, X5R, Walsin MLCC"
			(at 0 0 90)
			(layer "F.Fab")
			(hide yes)
			(effects
				(font
					(size 1.27 1.27)
					(thickness 0.15)
				)
			)
		)
		(property "Author" "Antmicro"
			(at 255.5 41.05 0)
			(layer "B.Fab")
			(hide yes)
			(effects
				(font
					(size 1 1)
					(thickness 0.15)
				)
				(justify mirror)
			)
		)
		(property "Dielectric" ""
			(at 255.5 41.05 0)
			(layer "B.Fab")
			(hide yes)
			(effects
				(font
					(size 1 1)
					(thickness 0.15)
				)
				(justify mirror)
			)
		)
		(property "License" "Apache-2.0"
			(at 255.5 41.05 0)
			(layer "B.Fab")
			(hide yes)
			(effects
				(font
					(size 1 1)
					(thickness 0.15)
				)
				(justify mirror)
			)
		)
		(property "MPN" "0402X104K6R3CT"
			(at 255.5 41.05 0)
			(layer "B.Fab")
			(hide yes)
			(effects
				(font
					(size 1 1)
					(thickness 0.15)
				)
				(justify mirror)
			)
		)
		(property "Manufacturer" "Walsin"
			(at 255.5 41.05 0)
			(layer "B.Fab")
			(hide yes)
			(effects
				(font
					(size 1 1)
					(thickness 0.15)
				)
				(justify mirror)
			)
		)
		(property "Public" "False"
			(at 255.5 41.05 0)
			(layer "B.Fab")
			(hide yes)
			(effects
				(font
					(size 1 1)
					(thickness 0.15)
				)
				(justify mirror)
			)
		)
		(property "Val" "100n"
			(at 255.5 41.05 0)
			(layer "B.Fab")
			(hide yes)
			(effects
				(font
					(size 1 1)
					(thickness 0.15)
				)
				(justify mirror)
			)
		)
		(property "Voltage" ""
			(at 255.5 41.05 0)
			(layer "B.Fab")
			(hide yes)
			(effects
				(font
					(size 1 1)
					(thickness 0.15)
				)
				(justify mirror)
			)
		)
		(sheetname "/DDR3/")
		(sheetfile "ddr3.kicad_sch")
		(attr smd)
		(fp_rect
			(start -0.925 0.47)
			(end 0.925 -0.47)
			(stroke
				(width 0.05)
				(type default)
			)
			(fill no)
			(layer "B.CrtYd")
		)
		(fp_line
			(start 0.504 -0.248)
			(end -0.494 -0.248)
			(stroke
				(width 0.15)
				(type solid)
			)
			(layer "B.Fab")
		)
		(fp_line
			(start -0.494 -0.248)
			(end -0.494 0.25)
			(stroke
				(width 0.15)
				(type solid)
			)
			(layer "B.Fab")
		)
		(fp_line
			(start 0.504 0.25)
			(end 0.504 -0.248)
			(stroke
				(width 0.15)
				(type solid)
			)
			(layer "B.Fab")
		)
		(fp_line
			(start -0.494 0.25)
			(end 0.504 0.25)
			(stroke
				(width 0.15)
				(type solid)
			)
			(layer "B.Fab")
		)
		(pad "1" smd roundrect
			(at -0.48 0 90)
			(size 0.59 0.64)
			(layers "B.Cu" "B.Mask" "B.Paste")
			(roundrect_rratio 0.25)
			(net 109 "Net-(C63-Pad1)")
			(pintype "passive")
		)
		(pad "2" smd roundrect
			(at 0.48 0 90)
			(size 0.59 0.64)
			(layers "B.Cu" "B.Mask" "B.Paste")
			(roundrect_rratio 0.25)
			(net 1 "GND")
			(pintype "passive")
		)
	)
	(footprint "antmicro-footprints:R_0402_1005Metric"
		(layer "B.Cu")
		(at 105.175 148.275 90)
		(descr "Resistor SMD 0402")
		(tags "resistor SMD 0402")
		(property "Reference" "R100"
			(at -3.625 0.375 90)
			(layer "B.SilkS")
			(effects
				(font
					(size 0.7 0.7)
					(thickness 0.15)
				)
				(justify right bottom mirror)
			)
		)
		(property "Value" "R_51R_0402"
			(at 0 -1.4 90)
			(layer "B.Fab")
			(effects
				(font
					(size 0.7 0.7)
					(thickness 0.15)
				)
				(justify right bottom mirror)
			)
		)
		(property "Datasheet" "https://www.bourns.com/docs/product-datasheets/cr.pdf"
			(at 0 0 90)
			(layer "F.Fab")
			(hide yes)
			(effects
				(font
					(size 1.27 1.27)
					(thickness 0.15)
				)
			)
		)
		(property "Description" "SMD Chip Resistor, 51 ohm, ± 1%, 63 mW, 0402 [1005 Metric], Thick Film, General Purpose"
			(at 0 0 90)
			(layer "F.Fab")
			(hide yes)
			(effects
				(font
					(size 1.27 1.27)
					(thickness 0.15)
				)
			)
		)
		(property "Author" "Antmicro"
			(at 253.45 43.1 0)
			(layer "B.Fab")
			(hide yes)
			(effects
				(font
					(size 1 1)
					(thickness 0.15)
				)
				(justify mirror)
			)
		)
		(property "License" "Apache-2.0"
			(at 253.45 43.1 0)
			(layer "B.Fab")
			(hide yes)
			(effects
				(font
					(size 1 1)
					(thickness 0.15)
				)
				(justify mirror)
			)
		)
		(property "MPN" "CR0402-FX-51R0GLF"
			(at 253.45 43.1 0)
			(layer "B.Fab")
			(hide yes)
			(effects
				(font
					(size 1 1)
					(thickness 0.15)
				)
				(justify mirror)
			)
		)
		(property "Manufacturer" "Bourns"
			(at 253.45 43.1 0)
			(layer "B.Fab")
			(hide yes)
			(effects
				(font
					(size 1 1)
					(thickness 0.15)
				)
				(justify mirror)
			)
		)
		(property "Tolerance" "1%"
			(at 253.45 43.1 0)
			(layer "B.Fab")
			(hide yes)
			(effects
				(font
					(size 1 1)
					(thickness 0.15)
				)
				(justify mirror)
			)
		)
		(property "Val" "51R"
			(at 253.45 43.1 0)
			(layer "B.Fab")
			(hide yes)
			(effects
				(font
					(size 1 1)
					(thickness 0.15)
				)
				(justify mirror)
			)
		)
		(sheetname "/DDR3/")
		(sheetfile "ddr3.kicad_sch")
		(attr smd exclude_from_pos_files exclude_from_bom dnp)
		(fp_rect
			(start -0.925 0.47)
			(end 0.925 -0.47)
			(stroke
				(width 0.05)
				(type default)
			)
			(fill no)
			(layer "B.CrtYd")
		)
		(fp_rect
			(start -0.5 0.25)
			(end 0.5 -0.25)
			(stroke
				(width 0.15)
				(type solid)
			)
			(fill no)
			(layer "B.Fab")
		)
		(pad "1" smd roundrect
			(at -0.48 0 90)
			(size 0.59 0.64)
			(layers "B.Cu" "B.Mask" "B.Paste")
			(roundrect_rratio 0.25)
			(net 109 "Net-(C63-Pad1)")
			(pintype "passive")
		)
		(pad "2" smd roundrect
			(at 0.48 0 90)
			(size 0.59 0.64)
			(layers "B.Cu" "B.Mask" "B.Paste")
			(roundrect_rratio 0.25)
			(net 478 "DDR3_CLK_N")
			(pintype "passive")
		)
	)
	(footprint "antmicro-footprints:C_0402_1005Metric"
		(layer "B.Cu")
		(at 107.275 114.475 -90)
		(descr "Capacitor SMD 0402")
		(tags "capacitor SMD 0402")
		(property "Reference" "C109"
			(at -1.475 -1.225 90)
			(layer "B.SilkS")
			(effects
				(font
					(size 0.7 0.7)
					(thickness 0.15)
				)
				(justify left bottom mirror)
			)
		)
		(property "Value" "C_470n_0402"
			(at 0 -1.4 90)
			(layer "B.Fab")
			(effects
				(font
					(size 0.7 0.7)
					(thickness 0.15)
				)
				(justify left bottom mirror)
			)
		)
		(property "Datasheet" "https://product.tdk.com/en/search/capacitor/ceramic/mlcc/info?part_no=C1005X5R1E474M050BB"
			(at 0 0 270)
			(layer "F.Fab")
			(hide yes)
			(effects
				(font
					(size 1.27 1.27)
					(thickness 0.15)
				)
			)
		)
		(property "Description" "SMD Multilayer Ceramic Capacitor, 0.47 µF, 25 V, 0402 [1005 Metric], ± 20%, X5R, C"
			(at 0 0 270)
			(layer "F.Fab")
			(hide yes)
			(effects
				(font
					(size 1.27 1.27)
					(thickness 0.15)
				)
			)
		)
		(property "Author" "Antmicro"
			(at -7.2 221.75 0)
			(layer "B.Fab")
			(hide yes)
			(effects
				(font
					(size 1 1)
					(thickness 0.15)
				)
				(justify mirror)
			)
		)
		(property "Dielectric" ""
			(at -7.2 221.75 0)
			(layer "B.Fab")
			(hide yes)
			(effects
				(font
					(size 1 1)
					(thickness 0.15)
				)
				(justify mirror)
			)
		)
		(property "License" "Apache-2.0"
			(at -7.2 221.75 0)
			(layer "B.Fab")
			(hide yes)
			(effects
				(font
					(size 1 1)
					(thickness 0.15)
				)
				(justify mirror)
			)
		)
		(property "MPN" "C1005X5R1E474M050BB"
			(at -7.2 221.75 0)
			(layer "B.Fab")
			(hide yes)
			(effects
				(font
					(size 1 1)
					(thickness 0.15)
				)
				(justify mirror)
			)
		)
		(property "Manufacturer" "TDK"
			(at -7.2 221.75 0)
			(layer "B.Fab")
			(hide yes)
			(effects
				(font
					(size 1 1)
					(thickness 0.15)
				)
				(justify mirror)
			)
		)
		(property "Val" "470n"
			(at -7.2 221.75 0)
			(layer "B.Fab")
			(hide yes)
			(effects
				(font
					(size 1 1)
					(thickness 0.15)
				)
				(justify mirror)
			)
		)
		(property "Voltage" ""
			(at -7.2 221.75 0)
			(layer "B.Fab")
			(hide yes)
			(effects
				(font
					(size 1 1)
					(thickness 0.15)
				)
				(justify mirror)
			)
		)
		(sheetname "/FPGA banks 34-35 & CFG/")
		(sheetfile "fpga-banks-34-25-cfg.kicad_sch")
		(attr smd)
		(fp_rect
			(start -0.925 0.47)
			(end 0.925 -0.47)
			(stroke
				(width 0.05)
				(type default)
			)
			(fill no)
			(layer "B.CrtYd")
		)
		(fp_line
			(start -0.494 0.25)
			(end 0.504 0.25)
			(stroke
				(width 0.15)
				(type solid)
			)
			(layer "B.Fab")
		)
		(fp_line
			(start 0.504 0.25)
			(end 0.504 -0.248)
			(stroke
				(width 0.15)
				(type solid)
			)
			(layer "B.Fab")
		)
		(fp_line
			(start -0.494 -0.248)
			(end -0.494 0.25)
			(stroke
				(width 0.15)
				(type solid)
			)
			(layer "B.Fab")
		)
		(fp_line
			(start 0.504 -0.248)
			(end -0.494 -0.248)
			(stroke
				(width 0.15)
				(type solid)
			)
			(layer "B.Fab")
		)
		(pad "1" smd roundrect
			(at -0.48 0 270)
			(size 0.59 0.64)
			(layers "B.Cu" "B.Mask" "B.Paste")
			(roundrect_rratio 0.25)
			(net 1 "GND")
			(pintype "passive")
		)
		(pad "2" smd roundrect
			(at 0.48 0 270)
			(size 0.59 0.64)
			(layers "B.Cu" "B.Mask" "B.Paste")
			(roundrect_rratio 0.25)
			(net 2 "VCC3V3")
			(pintype "passive")
		)
	)
)
